(kicad_pcb
	(version 20260206)
	(generator "pcbnew")
	(generator_version "10.0")
	(general
		(thickness 1.6)
		(legacy_teardrops no)
	)
	(paper "A4")
	(title_block
		(title "pdpb — Lightning_PDPB_BRD.brd")
		(comment 1 "Lightning (Wiwynn / Facebook NVMe JBOF) / footprints 504-504 of 1140")
	)
	(layers
		(0 "F.Cu" signal "TOP")
		(4 "In1.Cu" signal "L2GND")
		(6 "In2.Cu" signal "L3")
		(8 "In3.Cu" signal "L4VCC")
		(10 "In4.Cu" signal "L5VCC")
		(12 "In5.Cu" signal "L6")
		(14 "In6.Cu" signal "L7GND")
		(2 "B.Cu" signal "BOTTOM")
		(9 "F.Adhes" user "F.Adhesive")
		(11 "B.Adhes" user "B.Adhesive")
		(13 "F.Paste" user "Package Geometry/Pastemask Top")
		(15 "B.Paste" user "Package Geometry/Pastemask Bottom")
		(5 "F.SilkS" user "Ref Des/Silkscreen Top")
		(7 "B.SilkS" user "Ref Des/Silkscreen Bottom")
		(1 "F.Mask" user "Board Geometry/Soldermask Top")
		(3 "B.Mask" user "Board Geometry/Soldermask Bottom")
		(17 "Dwgs.User" user "User.Drawings")
		(19 "Cmts.User" user "User.Comments")
		(21 "Eco1.User" user "User.Eco1")
		(23 "Eco2.User" user "User.Eco2")
		(25 "Edge.Cuts" user "Board Geometry/Outline")
		(27 "Margin" user)
		(31 "F.CrtYd" user "Package Geometry/Place Bound Top")
		(29 "B.CrtYd" user "Package Geometry/Place Bound Bottom")
		(35 "F.Fab" user "Ref Des/Assembly Top")
		(33 "B.Fab" user "Ref Des/Assembly Bottom")
	)
	(footprint ""
		(layer "F.Cu")
		(at 20.850098 -335.330038 -90)
		(property "Reference" "J11"
			(at 0 0 270)
			(layer "F.SilkS")
			(hide yes)
			(effects
				(font
					(size 1.27 1.27)
				)
			)
		)
		(property "Value" "PCISLT68-14-GP-U1"
			(at -22.225 12.7508 270)
			(unlocked yes)
			(layer "F.Fab")
			(hide yes)
			(effects
				(font
					(size 1.016 1.016)
					(thickness 0.1524)
				)
			)
		)
		(property "Device Type" "SD-78827-0001"
			(at -22.225 11.2268 270)
			(unlocked yes)
			(layer "F.Fab")
			(hide yes)
			(effects
				(font
					(size 1.016 1.016)
					(thickness 0.1524)
				)
			)
		)
		(duplicate_pad_numbers_are_jumpers no)
		(fp_line
			(start -20.4724 12.0142)
			(end -20.4724 4.6736)
			(stroke
				(width 0.1524)
				(type default)
			)
			(layer "F.SilkS")
		)
		(fp_line
			(start -17.8435 12.0142)
			(end -20.4724 12.0142)
			(stroke
				(width 0.1524)
				(type default)
			)
			(layer "F.SilkS")
		)
		(fp_line
			(start 17.8435 12.0142)
			(end 17.8435 10.3124)
			(stroke
				(width 0.1524)
				(type default)
			)
			(layer "F.SilkS")
		)
		(fp_line
			(start 20.4724 12.0142)
			(end 17.8435 12.0142)
			(stroke
				(width 0.1524)
				(type default)
			)
			(layer "F.SilkS")
		)
		(fp_line
			(start -17.8435 10.3124)
			(end -17.8435 12.0142)
			(stroke
				(width 0.1524)
				(type default)
			)
			(layer "F.SilkS")
		)
		(fp_line
			(start 17.8435 10.3124)
			(end -17.8435 10.3124)
			(stroke
				(width 0.1524)
				(type default)
			)
			(layer "F.SilkS")
		)
		(fp_line
			(start -23.749 4.6736)
			(end -23.749 0.0254)
			(stroke
				(width 0.1524)
				(type default)
			)
			(layer "F.SilkS")
		)
		(fp_line
			(start -20.4724 4.6736)
			(end -23.749 4.6736)
			(stroke
				(width 0.1524)
				(type default)
			)
			(layer "F.SilkS")
		)
		(fp_line
			(start 20.4724 4.6736)
			(end 20.4724 12.0142)
			(stroke
				(width 0.1524)
				(type default)
			)
			(layer "F.SilkS")
		)
		(fp_line
			(start 23.749 4.6736)
			(end 20.4724 4.6736)
			(stroke
				(width 0.1524)
				(type default)
			)
			(layer "F.SilkS")
		)
		(fp_line
			(start -23.117556 2.896108)
			(end -23.117556 1.803908)
			(stroke
				(width 0.3048)
				(type default)
			)
			(layer "F.SilkS")
		)
		(fp_line
			(start 20.882356 2.896108)
			(end 20.882356 1.803908)
			(stroke
				(width 0.3048)
				(type default)
			)
			(layer "F.SilkS")
		)
		(fp_line
			(start -20.882356 1.803908)
			(end -20.882356 2.896108)
			(stroke
				(width 0.3048)
				(type default)
			)
			(layer "F.SilkS")
		)
		(fp_line
			(start 23.117556 1.803908)
			(end 23.117556 2.896108)
			(stroke
				(width 0.3048)
				(type default)
			)
			(layer "F.SilkS")
		)
		(fp_line
			(start -23.749 0.0254)
			(end -20.4724 0.0254)
			(stroke
				(width 0.1524)
				(type default)
			)
			(layer "F.SilkS")
		)
		(fp_line
			(start -20.4724 0.0254)
			(end -20.4724 -3.4036)
			(stroke
				(width 0.1524)
				(type default)
			)
			(layer "F.SilkS")
		)
		(fp_line
			(start 20.4724 0.0254)
			(end 23.749 0.0254)
			(stroke
				(width 0.1524)
				(type default)
			)
			(layer "F.SilkS")
		)
		(fp_line
			(start 23.749 0.0254)
			(end 23.749 4.6736)
			(stroke
				(width 0.1524)
				(type default)
			)
			(layer "F.SilkS")
		)
		(fp_line
			(start -20.4724 -3.4036)
			(end 20.4724 -3.4036)
			(stroke
				(width 0.1524)
				(type default)
			)
			(layer "F.SilkS")
		)
		(fp_line
			(start 20.4724 -3.4036)
			(end 20.4724 0.0254)
			(stroke
				(width 0.1524)
				(type default)
			)
			(layer "F.SilkS")
		)
		(fp_arc
			(start -20.882356 2.896108)
			(mid -21.999956 4.013708)
			(end -23.117556 2.896108)
			(stroke
				(width 0.3048)
				(type default)
			)
			(layer "F.SilkS")
		)
		(fp_arc
			(start 23.117556 2.896108)
			(mid 21.999956 4.013708)
			(end 20.882356 2.896108)
			(stroke
				(width 0.3048)
				(type default)
			)
			(layer "F.SilkS")
		)
		(fp_arc
			(start -23.117556 1.803908)
			(mid -21.999956 0.686308)
			(end -20.882356 1.803908)
			(stroke
				(width 0.3048)
				(type default)
			)
			(layer "F.SilkS")
		)
		(fp_arc
			(start 20.882356 1.803908)
			(mid 21.999956 0.686308)
			(end 23.117556 1.803908)
			(stroke
				(width 0.3048)
				(type default)
			)
			(layer "F.SilkS")
		)
		(fp_poly
			(pts
				(xy -20.2184 11.7602) (xy -20.2184 4.4196) (xy -23.495 4.4196) (xy -23.495 0.2794) (xy -20.2184 0.2794)
				(xy -20.2184 -3.1496) (xy 20.2184 -3.1496) (xy 20.2184 0.2794) (xy 23.495 0.2794) (xy 23.495 4.4196)
				(xy 20.2184 4.4196) (xy 20.2184 11.7602) (xy 18.0975 11.7602) (xy 18.0975 10.0584) (xy -18.0975 10.0584)
				(xy -18.0975 11.7602)
			)
			(stroke
				(width 0)
				(type default)
			)
			(fill no)
			(layer "F.CrtYd")
		)
		(fp_poly
			(pts
				(xy -21.2471 16.256) (xy -21.2471 4.9276) (xy -24.003 4.9276) (xy -24.003 -0.2286) (xy -20.7264 -0.2286)
				(xy -20.7264 -3.6576) (xy 20.7264 -3.6576) (xy 20.7264 -0.2286) (xy 24.003 -0.2286) (xy 24.003 -0.00635)
				(xy 20.2184 -0.00635) (xy 20.2184 -3.1496) (xy -20.2184 -3.1496) (xy -20.2184 0.2794) (xy -23.495 0.2794)
				(xy -23.495 4.4196) (xy -20.2184 4.4196) (xy -20.2184 11.7602) (xy -18.0975 11.7602) (xy -18.0975 10.0584)
				(xy 18.0975 10.0584) (xy 18.0975 11.7602) (xy 20.2184 11.7602) (xy 20.2184 4.4196) (xy 23.495 4.4196)
				(xy 23.495 0.2794) (xy 20.2184 0.2794) (xy 20.2184 0.00635) (xy 24.003 0.00635) (xy 24.003 4.9276)
				(xy 21.2471 4.9276) (xy 21.2471 16.256)
			)
			(stroke
				(width 0)
				(type default)
			)
			(fill no)
			(layer "F.CrtYd")
		)
		(fp_poly
			(pts
				(xy -21.2471 16.256) (xy -21.2471 4.9276) (xy -24.003 4.9276) (xy -24.003 -0.2286) (xy -20.7264 -0.2286)
				(xy -20.7264 -3.6576) (xy 20.7264 -3.6576) (xy 20.7264 -0.2286) (xy 24.003 -0.2286) (xy 24.003 4.9276)
				(xy 21.2471 4.9276) (xy 21.2471 16.256)
			)
			(stroke
				(width 0)
				(type default)
			)
			(fill no)
			(layer "F.Fab")
		)
		(pad "" np_thru_hole circle
			(at -18.999962 0 270)
			(size 0.254 0.254)
			(drill 1.8542)
			(layers "*.Cu" "*.Mask")
			(clearance 1.1557)
			(thermal_gap 1.1557)
		)
		(pad "" np_thru_hole circle
			(at 18.999962 0 270)
			(size 0.254 0.254)
			(drill 1.8542)
			(layers "*.Cu" "*.Mask")
			(clearance 1.1557)
			(thermal_gap 1.1557)
		)
		(pad "E1" smd rect
			(at -7.079996 1.240028 270)
			(size 0.508 2.0066)
			(layers "F.Cu" "F.Mask" "F.Paste")
			(net "PE_CLK100M_DR11_2_P")
		)
		(pad "E2" smd rect
			(at -6.279896 1.240028 270)
			(size 0.508 2.0066)
			(layers "F.Cu" "F.Mask" "F.Paste")
			(net "PE_CLK100M_DR11_2_N")
		)
		(pad "E3" smd rect
			(at -5.48005 1.240028 270)
			(size 0.508 2.0066)
			(layers "F.Cu" "F.Mask" "F.Paste")
			(net "P3V3")
		)
		(pad "E4" smd rect
			(at -4.67995 1.240028 270)
			(size 0.508 2.0066)
			(layers "F.Cu" "F.Mask" "F.Paste")
			(net "SSD11_PERST_N")
		)
		(pad "E5" smd rect
			(at -3.880104 1.240028 270)
			(size 0.508 2.0066)
			(layers "F.Cu" "F.Mask" "F.Paste")
			(net "SSD11_PERST_N")
		)
		(pad "E6" smd rect
			(at -3.080004 1.240028 270)
			(size 0.508 2.0066)
			(layers "F.Cu" "F.Mask" "F.Paste")
			(net "Net_1269")
		)
		(pad "E7" smd rect
			(at -15.48003 -1.949958 270)
			(size 0.508 2.0066)
			(layers "F.Cu" "F.Mask" "F.Paste")
			(net "PE_CLK100M_DR11_1_P")
		)
		(pad "E8" smd rect
			(at -14.67993 -1.949958 270)
			(size 0.508 2.0066)
			(layers "F.Cu" "F.Mask" "F.Paste")
			(net "PE_CLK100M_DR11_1_N")
		)
		(pad "E9" smd rect
			(at -13.880084 -1.949958 270)
			(size 0.508 2.0066)
			(layers "F.Cu" "F.Mask" "F.Paste")
			(net "GND")
		)
		(pad "E10" smd rect
			(at -13.079984 -1.949958 270)
			(size 0.508 2.0066)
			(layers "F.Cu" "F.Mask" "F.Paste")
			(net "PE_TX1_DR11_N")
		)
		(pad "E11" smd rect
			(at -12.279884 -1.949958 270)
			(size 0.508 2.0066)
			(layers "F.Cu" "F.Mask" "F.Paste")
			(net "PE_TX1_DR11_P")
		)
		(pad "E12" smd rect
			(at -11.480038 -1.949958 270)
			(size 0.508 2.0066)
			(layers "F.Cu" "F.Mask" "F.Paste")
			(net "GND")
		)
		(pad "E13" smd rect
			(at -10.679938 -1.949958 270)
			(size 0.508 2.0066)
			(layers "F.Cu" "F.Mask" "F.Paste")
			(net "PE_RX1_DR11_N")
		)
		(pad "E14" smd rect
			(at -9.880092 -1.949958 270)
			(size 0.508 2.0066)
			(layers "F.Cu" "F.Mask" "F.Paste")
			(net "PE_RX1_DR11_P")
		)
		(pad "E15" smd rect
			(at -9.079992 -1.949958 270)
			(size 0.508 2.0066)
			(layers "F.Cu" "F.Mask" "F.Paste")
			(net "GND")
		)
		(pad "E16" smd rect
			(at -8.279892 -1.949958 270)
			(size 0.508 2.0066)
			(layers "F.Cu" "F.Mask" "F.Paste")
			(net "Net_1276")
		)
		(pad "E17" smd rect
			(at 9.320022 -1.949958 270)
			(size 0.508 2.0066)
			(layers "F.Cu" "F.Mask" "F.Paste")
			(net "PE_TX4_DR11_N")
		)
		(pad "E18" smd rect
			(at 10.120122 -1.949958 270)
			(size 0.508 2.0066)
			(layers "F.Cu" "F.Mask" "F.Paste")
			(net "PE_TX4_DR11_P")
		)
		(pad "E19" smd rect
			(at 10.919968 -1.949958 270)
			(size 0.508 2.0066)
			(layers "F.Cu" "F.Mask" "F.Paste")
			(net "GND")
		)
		(pad "E20" smd rect
			(at 11.720068 -1.949958 270)
			(size 0.508 2.0066)
			(layers "F.Cu" "F.Mask" "F.Paste")
			(net "PE_RX4_DR11_N")
		)
		(pad "E21" smd rect
			(at 12.519914 -1.949958 270)
			(size 0.508 2.0066)
			(layers "F.Cu" "F.Mask" "F.Paste")
			(net "PE_RX4_DR11_P")
		)
		(pad "E22" smd rect
			(at 13.320014 -1.949958 270)
			(size 0.508 2.0066)
			(layers "F.Cu" "F.Mask" "F.Paste")
			(net "GND")
		)
		(pad "E23" smd rect
			(at 14.120114 -1.949958 270)
			(size 0.508 2.0066)
			(layers "F.Cu" "F.Mask" "F.Paste")
			(net "SCL_DR11_R")
		)
		(pad "E24" smd rect
			(at 14.91996 -1.949958 270)
			(size 0.508 2.0066)
			(layers "F.Cu" "F.Mask" "F.Paste")
			(net "SDA_DR11_R")
		)
		(pad "E25" smd rect
			(at 15.72006 -1.949958 270)
			(size 0.508 2.0066)
			(layers "F.Cu" "F.Mask" "F.Paste")
			(net "DUALPORTEN#11")
		)
		(pad "P1" smd rect
			(at -1.905 0.824992 270)
			(size 0.6604 2.0574)
			(layers "F.Cu" "F.Mask" "F.Paste")
			(net "Net_1272")
		)
		(pad "P2" smd rect
			(at -0.635 0.824992 270)
			(size 0.6604 2.0574)
			(layers "F.Cu" "F.Mask" "F.Paste")
			(net "Net_1271")
		)
		(pad "P3" smd rect
			(at 0.635 0.824992 270)
			(size 0.6604 2.0574)
			(layers "F.Cu" "F.Mask" "F.Paste")
			(net "Net_1270")
		)
		(pad "P4" smd rect
			(at 1.905 0.824992 270)
			(size 0.6604 2.0574)
			(layers "F.Cu" "F.Mask" "F.Paste")
			(net "SSD11_CLK0_OE_N")
		)
		(pad "P5" smd rect
			(at 3.175 0.824992 270)
			(size 0.6604 2.0574)
			(layers "F.Cu" "F.Mask" "F.Paste")
			(net "GND")
		)
		(pad "P6" smd rect
			(at 4.445 0.824992 270)
			(size 0.6604 2.0574)
			(layers "F.Cu" "F.Mask" "F.Paste")
			(net "GND")
		)
		(pad "P7" smd rect
			(at 5.715 0.824992 270)
			(size 0.6604 2.0574)
			(layers "F.Cu" "F.Mask" "F.Paste")
			(net "Net_99")
		)
		(pad "P8" smd rect
			(at 6.985 0.824992 270)
			(size 0.6604 2.0574)
			(layers "F.Cu" "F.Mask" "F.Paste")
			(net "Net_72")
		)
		(pad "P9" smd rect
			(at 8.255 0.824992 270)
			(size 0.6604 2.0574)
			(layers "F.Cu" "F.Mask" "F.Paste")
			(net "Net_86")
		)
		(pad "P10" smd rect
			(at 9.525 0.824992 270)
			(size 0.6604 2.0574)
			(layers "F.Cu" "F.Mask" "F.Paste")
			(net "SSD_PRSNT_NET11")
		)
		(pad "P11" smd rect
			(at 10.795 0.824992 270)
			(size 0.6604 2.0574)
			(layers "F.Cu" "F.Mask" "F.Paste")
			(net "SSD_ACT_DR11")
		)
		(pad "P12" smd rect
			(at 12.065 0.824992 270)
			(size 0.6604 2.0574)
			(layers "F.Cu" "F.Mask" "F.Paste")
			(net "GND")
		)
		(pad "P13" smd rect
			(at 13.335 0.824992 270)
			(size 0.6604 2.0574)
			(layers "F.Cu" "F.Mask" "F.Paste")
			(net "12V_PRECH_SSD11")
		)
		(pad "P14" smd rect
			(at 14.605 0.824992 270)
			(size 0.6604 2.0574)
			(layers "F.Cu" "F.Mask" "F.Paste")
			(net "P12V_SSD11")
		)
		(pad "P15" smd rect
			(at 15.875 0.824992 270)
			(size 0.6604 2.0574)
			(layers "F.Cu" "F.Mask" "F.Paste")
			(net "P12V_SSD11")
		)
		(pad "PTH1" thru_hole oval
			(at -21.999956 2.350008 270)
			(size 1.524 2.6162)
			(drill oval 0.8128 1.905)
			(layers "*.Cu" "*.Mask")
			(remove_unused_layers no)
			(net "Net_1281")
			(clearance 0.1524)
			(thermal_gap 0.1524)
		)
		(pad "PTH2" thru_hole oval
			(at 21.999956 2.350008 270)
			(size 1.524 2.6162)
			(drill oval 0.8128 1.905)
			(layers "*.Cu" "*.Mask")
			(remove_unused_layers no)
			(net "Net_1265")
			(clearance 0.1524)
			(thermal_gap 0.1524)
		)
		(pad "S1" smd rect
			(at -15.875 0.824992 270)
			(size 0.6604 2.0574)
			(layers "F.Cu" "F.Mask" "F.Paste")
			(net "GND")
		)
		(pad "S2" smd rect
			(at -14.605 0.824992 270)
			(size 0.6604 2.0574)
			(layers "F.Cu" "F.Mask" "F.Paste")
			(net "Net_1280")
		)
		(pad "S3" smd rect
			(at -13.335 0.824992 270)
			(size 0.6604 2.0574)
			(layers "F.Cu" "F.Mask" "F.Paste")
			(net "Net_1279")
		)
		(pad "S4" smd rect
			(at -12.065 0.824992 270)
			(size 0.6604 2.0574)
			(layers "F.Cu" "F.Mask" "F.Paste")
			(net "GND")
		)
		(pad "S5" smd rect
			(at -10.795 0.824992 270)
			(size 0.6604 2.0574)
			(layers "F.Cu" "F.Mask" "F.Paste")
			(net "Net_1278")
		)
		(pad "S6" smd rect
			(at -9.525 0.824992 270)
			(size 0.6604 2.0574)
			(layers "F.Cu" "F.Mask" "F.Paste")
			(net "Net_1277")
		)
		(pad "S7" smd rect
			(at -8.255 0.824992 270)
			(size 0.6604 2.0574)
			(layers "F.Cu" "F.Mask" "F.Paste")
			(net "GND")
		)
		(pad "S8" smd rect
			(at -7.480046 -1.949958 270)
			(size 0.508 2.0066)
			(layers "F.Cu" "F.Mask" "F.Paste")
			(net "GND")
		)
		(pad "S9" smd rect
			(at -6.679946 -1.949958 270)
			(size 0.508 2.0066)
			(layers "F.Cu" "F.Mask" "F.Paste")
			(net "Net_1275")
		)
		(pad "S10" smd rect
			(at -5.8801 -1.949958 270)
			(size 0.508 2.0066)
			(layers "F.Cu" "F.Mask" "F.Paste")
			(net "Net_1274")
		)
		(pad "S11" smd rect
			(at -5.08 -1.949958 270)
			(size 0.508 2.0066)
			(layers "F.Cu" "F.Mask" "F.Paste")
			(net "GND")
		)
		(pad "S12" smd rect
			(at -4.2799 -1.949958 270)
			(size 0.508 2.0066)
			(layers "F.Cu" "F.Mask" "F.Paste")
			(net "Net_1273")
		)
		(pad "S13" smd rect
			(at -3.480054 -1.949958 270)
			(size 0.508 2.0066)
			(layers "F.Cu" "F.Mask" "F.Paste")
			(net "Net_1268")
		)
		(pad "S14" smd rect
			(at -2.679954 -1.949958 270)
			(size 0.508 2.0066)
			(layers "F.Cu" "F.Mask" "F.Paste")
			(net "GND")
		)
		(pad "S15" smd rect
			(at -1.880108 -1.949958 270)
			(size 0.508 2.0066)
			(layers "F.Cu" "F.Mask" "F.Paste")
			(net "Net_1267")
		)
		(pad "S16" smd rect
			(at -1.080008 -1.949958 270)
			(size 0.508 2.0066)
			(layers "F.Cu" "F.Mask" "F.Paste")
			(net "GND")
		)
		(pad "S17" smd rect
			(at -0.279908 -1.949958 270)
			(size 0.508 2.0066)
			(layers "F.Cu" "F.Mask" "F.Paste")
			(net "PE_TX2_DR11_N")
		)
		(pad "S18" smd rect
			(at 0.519938 -1.949958 270)
			(size 0.508 2.0066)
			(layers "F.Cu" "F.Mask" "F.Paste")
			(net "PE_TX2_DR11_P")
		)
		(pad "S19" smd rect
			(at 1.320038 -1.949958 270)
			(size 0.508 2.0066)
			(layers "F.Cu" "F.Mask" "F.Paste")
			(net "GND")
		)
		(pad "S20" smd rect
			(at 2.119884 -1.949958 270)
			(size 0.508 2.0066)
			(layers "F.Cu" "F.Mask" "F.Paste")
			(net "PE_RX2_DR11_N")
		)
		(pad "S21" smd rect
			(at 2.919984 -1.949958 270)
			(size 0.508 2.0066)
			(layers "F.Cu" "F.Mask" "F.Paste")
			(net "PE_RX2_DR11_P")
		)
		(pad "S22" smd rect
			(at 3.720084 -1.949958 270)
			(size 0.508 2.0066)
			(layers "F.Cu" "F.Mask" "F.Paste")
			(net "GND")
		)
		(pad "S23" smd rect
			(at 4.51993 -1.949958 270)
			(size 0.508 2.0066)
			(layers "F.Cu" "F.Mask" "F.Paste")
			(net "PE_TX3_DR11_N")
		)
		(pad "S24" smd rect
			(at 5.32003 -1.949958 270)
			(size 0.508 2.0066)
			(layers "F.Cu" "F.Mask" "F.Paste")
			(net "PE_TX3_DR11_P")
		)
		(pad "S25" smd rect
			(at 6.119876 -1.949958 270)
			(size 0.508 2.0066)
			(layers "F.Cu" "F.Mask" "F.Paste")
			(net "GND")
		)
		(pad "S26" smd rect
			(at 6.919976 -1.949958 270)
			(size 0.508 2.0066)
			(layers "F.Cu" "F.Mask" "F.Paste")
			(net "PE_RX3_DR11_N")
		)
		(pad "S27" smd rect
			(at 7.720076 -1.949958 270)
			(size 0.508 2.0066)
			(layers "F.Cu" "F.Mask" "F.Paste")
			(net "PE_RX3_DR11_P")
		)
		(pad "S28" smd rect
			(at 8.519922 -1.949958 270)
			(size 0.508 2.0066)
			(layers "F.Cu" "F.Mask" "F.Paste")
			(net "GND")
		)
		(zone
			(layers "F.Cu" "B.Cu" "In1.Cu" "In2.Cu" "In3.Cu" "In4.Cu" "In5.Cu" "In6.Cu")
			(hatch none 0.5)
			(connect_pads
				(clearance 0)
			)
			(min_thickness 0.25)
			(keepout
				(tracks not_allowed)
				(vias allowed)
				(pads allowed)
				(copperpour not_allowed)
				(footprints allowed)
			)
			(placement
				(enabled no)
				(sheetname "")
			)
			(fill
				(thermal_gap 0.5)
				(thermal_bridge_width 0.5)
				(island_removal_mode 0)
			)
			(polygon
				(pts
					(arc
						(start 22.081998 -354.33)
						(mid 19.618198 -354.33)
						(end 22.081998 -354.33)
					)
				)
			)
		)
		(zone
			(layers "F.Cu" "B.Cu" "In1.Cu" "In2.Cu" "In3.Cu" "In4.Cu" "In5.Cu" "In6.Cu")
			(hatch none 0.5)
			(connect_pads
				(clearance 0)
			)
			(min_thickness 0.25)
			(keepout
				(tracks not_allowed)
				(vias allowed)
				(pads allowed)
				(copperpour not_allowed)
				(footprints allowed)
			)
			(placement
				(enabled no)
				(sheetname "")
			)
			(fill
				(thermal_gap 0.5)
				(thermal_bridge_width 0.5)
				(island_removal_mode 0)
			)
			(polygon
				(pts
					(arc
						(start 22.081998 -316.330076)
						(mid 19.618198 -316.330076)
						(end 22.081998 -316.330076)
					)
				)
			)
		)
	)
)
